(kicad_pcb
	(version 20260206)
	(generator "pcbnew")
	(generator_version "10.0")
	(general
		(thickness 1.6)
		(legacy_teardrops no)
	)
	(paper "A4")
	(title_block
		(title "04192023_DAF0TMB3IC0_F0TG_MB_C_brd_V02_OCP.brd")
		(comment 1 "Grand Teton / footprints 1257-1263 of 8354")
	)
	(layers
		(0 "F.Cu" signal "TOP")
		(4 "In1.Cu" signal "GND")
		(6 "In2.Cu" signal "IN1")
		(8 "In3.Cu" signal "GND1")
		(10 "In4.Cu" signal "IN2")
		(12 "In5.Cu" signal "GND2")
		(14 "In6.Cu" signal "IN3")
		(16 "In7.Cu" signal "GND3")
		(18 "In8.Cu" signal "VCC")
		(20 "In9.Cu" signal "VCC1")
		(22 "In10.Cu" signal "GND4")
		(24 "In11.Cu" signal "IN4")
		(26 "In12.Cu" signal "GND5")
		(28 "In13.Cu" signal "IN5")
		(30 "In14.Cu" signal "GND6")
		(32 "In15.Cu" signal "IN6")
		(34 "In16.Cu" signal "GND7")
		(2 "B.Cu" signal "BOTTOM")
		(9 "F.Adhes" user "F.Adhesive")
		(11 "B.Adhes" user "B.Adhesive")
		(13 "F.Paste" user "Package Geometry/Pastemask Top")
		(15 "B.Paste" user "Package Geometry/Pastemask Bottom")
		(5 "F.SilkS" user "Ref Des/Silkscreen Top")
		(7 "B.SilkS" user "Ref Des/Silkscreen Bottom")
		(1 "F.Mask" user "Board Geometry/Soldermask Top")
		(3 "B.Mask" user "Board Geometry/Soldermask Bottom")
		(17 "Dwgs.User" user "User.Drawings")
		(19 "Cmts.User" user "User.Comments")
		(21 "Eco1.User" user "User.Eco1")
		(23 "Eco2.User" user "User.Eco2")
		(25 "Edge.Cuts" user "Board Geometry/Outline")
		(27 "Margin" user)
		(31 "F.CrtYd" user "Package Geometry/Place Bound Top")
		(29 "B.CrtYd" user "Package Geometry/Place Bound Bottom")
		(35 "F.Fab" user "Ref Des/Assembly Top")
		(33 "B.Fab" user "Ref Des/Assembly Bottom")
	)
	(footprint ""
		(layer "F.Cu")
		(at 70.713854 -148.635212)
		(property "Reference" "PC62"
			(at 0 0 0)
			(layer "F.SilkS")
			(hide yes)
			(effects
				(font
					(size 1.27 1.27)
				)
			)
		)
		(property "Value" ""
			(at 0 0 0)
			(layer "F.Fab")
			(effects
				(font
					(size 1.27 1.27)
				)
			)
		)
		(duplicate_pad_numbers_are_jumpers no)
		(fp_line
			(start -0.7874 -0.4064)
			(end 0.7874 -0.4064)
			(stroke
				(width 0.1524)
				(type default)
			)
			(layer "F.SilkS")
		)
		(fp_line
			(start -0.7874 0.4064)
			(end -0.7874 -0.4064)
			(stroke
				(width 0.1524)
				(type default)
			)
			(layer "F.SilkS")
		)
		(fp_line
			(start 0.7874 -0.4064)
			(end 0.7874 0.4064)
			(stroke
				(width 0.1524)
				(type default)
			)
			(layer "F.SilkS")
		)
		(fp_line
			(start 0.7874 0.4064)
			(end -0.7874 0.4064)
			(stroke
				(width 0.1524)
				(type default)
			)
			(layer "F.SilkS")
		)
		(fp_line
			(start -0.67945 -0.305054)
			(end -0.12065 -0.305054)
			(stroke
				(width 0.1)
				(type default)
			)
			(layer "F.Fab")
		)
		(fp_line
			(start -0.67945 0.3048)
			(end -0.67945 -0.305054)
			(stroke
				(width 0.1)
				(type default)
			)
			(layer "F.Fab")
		)
		(fp_line
			(start -0.12065 -0.305054)
			(end -0.12065 -0.2794)
			(stroke
				(width 0.1)
				(type default)
			)
			(layer "F.Fab")
		)
		(fp_line
			(start -0.12065 -0.2794)
			(end 0.12065 -0.2794)
			(stroke
				(width 0.1)
				(type default)
			)
			(layer "F.Fab")
		)
		(fp_line
			(start -0.12065 0.2794)
			(end -0.12065 0.3048)
			(stroke
				(width 0.1)
				(type default)
			)
			(layer "F.Fab")
		)
		(fp_line
			(start -0.12065 0.3048)
			(end -0.67945 0.3048)
			(stroke
				(width 0.1)
				(type default)
			)
			(layer "F.Fab")
		)
		(fp_line
			(start 0.120396 0.2794)
			(end -0.12065 0.2794)
			(stroke
				(width 0.1)
				(type default)
			)
			(layer "F.Fab")
		)
		(fp_line
			(start 0.120396 0.3048)
			(end 0.120396 0.2794)
			(stroke
				(width 0.1)
				(type default)
			)
			(layer "F.Fab")
		)
		(fp_line
			(start 0.12065 -0.3048)
			(end 0.67945 -0.3048)
			(stroke
				(width 0.1)
				(type default)
			)
			(layer "F.Fab")
		)
		(fp_line
			(start 0.12065 -0.2794)
			(end 0.12065 -0.3048)
			(stroke
				(width 0.1)
				(type default)
			)
			(layer "F.Fab")
		)
		(fp_line
			(start 0.67945 -0.3048)
			(end 0.67945 0.3048)
			(stroke
				(width 0.1)
				(type default)
			)
			(layer "F.Fab")
		)
		(fp_line
			(start 0.67945 0.3048)
			(end 0.120396 0.3048)
			(stroke
				(width 0.1)
				(type default)
			)
			(layer "F.Fab")
		)
		(pad "1" smd circle
			(at -0.40005 0)
			(size 0 0)
			(layers "F.Cu" "F.Mask" "F.Paste")
			(net "PVDD18_S5_P1_REF")
		)
		(pad "2" smd circle
			(at 0.40005 0)
			(size 0 0)
			(layers "F.Cu" "F.Mask" "F.Paste")
			(net "PVDD18_SS_P1_RGND")
		)
	)
	(footprint ""
		(layer "F.Cu")
		(at 17.045432 -107.631484)
		(property "Reference" "R4483"
			(at 0 0 0)
			(layer "F.SilkS")
			(hide yes)
			(effects
				(font
					(size 1.27 1.27)
				)
			)
		)
		(property "Value" ""
			(at 0 0 0)
			(layer "F.Fab")
			(effects
				(font
					(size 1.27 1.27)
				)
			)
		)
		(duplicate_pad_numbers_are_jumpers no)
		(fp_line
			(start -0.7874 -0.4064)
			(end 0.7874 -0.4064)
			(stroke
				(width 0.1524)
				(type default)
			)
			(layer "F.SilkS")
		)
		(fp_line
			(start -0.7874 0.4064)
			(end -0.7874 -0.4064)
			(stroke
				(width 0.1524)
				(type default)
			)
			(layer "F.SilkS")
		)
		(fp_line
			(start 0.7874 -0.4064)
			(end 0.7874 0.4064)
			(stroke
				(width 0.1524)
				(type default)
			)
			(layer "F.SilkS")
		)
		(fp_line
			(start 0.7874 0.4064)
			(end -0.7874 0.4064)
			(stroke
				(width 0.1524)
				(type default)
			)
			(layer "F.SilkS")
		)
		(fp_line
			(start -0.67945 -0.305054)
			(end -0.12065 -0.305054)
			(stroke
				(width 0.1)
				(type default)
			)
			(layer "F.Fab")
		)
		(fp_line
			(start -0.67945 0.3048)
			(end -0.67945 -0.305054)
			(stroke
				(width 0.1)
				(type default)
			)
			(layer "F.Fab")
		)
		(fp_line
			(start -0.12065 -0.305054)
			(end -0.12065 -0.2794)
			(stroke
				(width 0.1)
				(type default)
			)
			(layer "F.Fab")
		)
		(fp_line
			(start -0.12065 -0.2794)
			(end 0.12065 -0.2794)
			(stroke
				(width 0.1)
				(type default)
			)
			(layer "F.Fab")
		)
		(fp_line
			(start -0.12065 0.2794)
			(end -0.12065 0.3048)
			(stroke
				(width 0.1)
				(type default)
			)
			(layer "F.Fab")
		)
		(fp_line
			(start -0.12065 0.3048)
			(end -0.67945 0.3048)
			(stroke
				(width 0.1)
				(type default)
			)
			(layer "F.Fab")
		)
		(fp_line
			(start 0.120396 0.2794)
			(end -0.12065 0.2794)
			(stroke
				(width 0.1)
				(type default)
			)
			(layer "F.Fab")
		)
		(fp_line
			(start 0.120396 0.3048)
			(end 0.120396 0.2794)
			(stroke
				(width 0.1)
				(type default)
			)
			(layer "F.Fab")
		)
		(fp_line
			(start 0.12065 -0.3048)
			(end 0.67945 -0.3048)
			(stroke
				(width 0.1)
				(type default)
			)
			(layer "F.Fab")
		)
		(fp_line
			(start 0.12065 -0.2794)
			(end 0.12065 -0.3048)
			(stroke
				(width 0.1)
				(type default)
			)
			(layer "F.Fab")
		)
		(fp_line
			(start 0.67945 -0.3048)
			(end 0.67945 0.3048)
			(stroke
				(width 0.1)
				(type default)
			)
			(layer "F.Fab")
		)
		(fp_line
			(start 0.67945 0.3048)
			(end 0.120396 0.3048)
			(stroke
				(width 0.1)
				(type default)
			)
			(layer "F.Fab")
		)
		(pad "1" smd circle
			(at -0.40005 0)
			(size 0 0)
			(layers "F.Cu" "F.Mask" "F.Paste")
			(net "USB2_HOST_BMC_B_BUF_DN")
		)
		(pad "2" smd circle
			(at 0.40005 0)
			(size 0 0)
			(layers "F.Cu" "F.Mask" "F.Paste")
			(net "GND")
		)
	)
	(footprint ""
		(layer "F.Cu")
		(at 15.58417 -71.210678)
		(property "Reference" "C1810"
			(at 0 0 0)
			(layer "F.SilkS")
			(hide yes)
			(effects
				(font
					(size 1.27 1.27)
				)
			)
		)
		(property "Value" ""
			(at 0 0 0)
			(layer "F.Fab")
			(effects
				(font
					(size 1.27 1.27)
				)
			)
		)
		(duplicate_pad_numbers_are_jumpers no)
		(fp_line
			(start -0.7874 -0.4064)
			(end 0.7874 -0.4064)
			(stroke
				(width 0.1524)
				(type default)
			)
			(layer "F.SilkS")
		)
		(fp_line
			(start -0.7874 0.4064)
			(end -0.7874 -0.4064)
			(stroke
				(width 0.1524)
				(type default)
			)
			(layer "F.SilkS")
		)
		(fp_line
			(start 0.7874 -0.4064)
			(end 0.7874 0.4064)
			(stroke
				(width 0.1524)
				(type default)
			)
			(layer "F.SilkS")
		)
		(fp_line
			(start 0.7874 0.4064)
			(end -0.7874 0.4064)
			(stroke
				(width 0.1524)
				(type default)
			)
			(layer "F.SilkS")
		)
		(fp_line
			(start -0.67945 -0.305054)
			(end -0.12065 -0.305054)
			(stroke
				(width 0.1)
				(type default)
			)
			(layer "F.Fab")
		)
		(fp_line
			(start -0.67945 0.3048)
			(end -0.67945 -0.305054)
			(stroke
				(width 0.1)
				(type default)
			)
			(layer "F.Fab")
		)
		(fp_line
			(start -0.12065 -0.305054)
			(end -0.12065 -0.2794)
			(stroke
				(width 0.1)
				(type default)
			)
			(layer "F.Fab")
		)
		(fp_line
			(start -0.12065 -0.2794)
			(end 0.12065 -0.2794)
			(stroke
				(width 0.1)
				(type default)
			)
			(layer "F.Fab")
		)
		(fp_line
			(start -0.12065 0.2794)
			(end -0.12065 0.3048)
			(stroke
				(width 0.1)
				(type default)
			)
			(layer "F.Fab")
		)
		(fp_line
			(start -0.12065 0.3048)
			(end -0.67945 0.3048)
			(stroke
				(width 0.1)
				(type default)
			)
			(layer "F.Fab")
		)
		(fp_line
			(start 0.120396 0.2794)
			(end -0.12065 0.2794)
			(stroke
				(width 0.1)
				(type default)
			)
			(layer "F.Fab")
		)
		(fp_line
			(start 0.120396 0.3048)
			(end 0.120396 0.2794)
			(stroke
				(width 0.1)
				(type default)
			)
			(layer "F.Fab")
		)
		(fp_line
			(start 0.12065 -0.3048)
			(end 0.67945 -0.3048)
			(stroke
				(width 0.1)
				(type default)
			)
			(layer "F.Fab")
		)
		(fp_line
			(start 0.12065 -0.2794)
			(end 0.12065 -0.3048)
			(stroke
				(width 0.1)
				(type default)
			)
			(layer "F.Fab")
		)
		(fp_line
			(start 0.67945 -0.3048)
			(end 0.67945 0.3048)
			(stroke
				(width 0.1)
				(type default)
			)
			(layer "F.Fab")
		)
		(fp_line
			(start 0.67945 0.3048)
			(end 0.120396 0.3048)
			(stroke
				(width 0.1)
				(type default)
			)
			(layer "F.Fab")
		)
		(pad "1" smd circle
			(at -0.40005 0)
			(size 0 0)
			(layers "F.Cu" "F.Mask" "F.Paste")
			(net "P3V3_AUX")
		)
		(pad "2" smd circle
			(at 0.40005 0)
			(size 0 0)
			(layers "F.Cu" "F.Mask" "F.Paste")
			(net "GND")
		)
	)
	(footprint ""
		(layer "F.Cu")
		(at 428.287688 -351.13849 -90)
		(property "Reference" "PC206_11P0_2"
			(at 0 0 270)
			(layer "F.SilkS")
			(hide yes)
			(effects
				(font
					(size 1.27 1.27)
				)
			)
		)
		(property "Value" ""
			(at 0 0 270)
			(layer "F.Fab")
			(effects
				(font
					(size 1.27 1.27)
				)
			)
		)
		(duplicate_pad_numbers_are_jumpers no)
		(fp_line
			(start -0.7874 0.4064)
			(end -0.7874 -0.4064)
			(stroke
				(width 0.1524)
				(type default)
			)
			(layer "F.SilkS")
		)
		(fp_line
			(start 0.7874 0.4064)
			(end -0.7874 0.4064)
			(stroke
				(width 0.1524)
				(type default)
			)
			(layer "F.SilkS")
		)
		(fp_line
			(start -0.7874 -0.4064)
			(end 0.7874 -0.4064)
			(stroke
				(width 0.1524)
				(type default)
			)
			(layer "F.SilkS")
		)
		(fp_line
			(start 0.7874 -0.4064)
			(end 0.7874 0.4064)
			(stroke
				(width 0.1524)
				(type default)
			)
			(layer "F.SilkS")
		)
		(fp_line
			(start -0.67945 0.3048)
			(end -0.67945 -0.305054)
			(stroke
				(width 0.1)
				(type default)
			)
			(layer "F.Fab")
		)
		(fp_line
			(start -0.12065 0.3048)
			(end -0.67945 0.3048)
			(stroke
				(width 0.1)
				(type default)
			)
			(layer "F.Fab")
		)
		(fp_line
			(start 0.120396 0.3048)
			(end 0.120396 0.2794)
			(stroke
				(width 0.1)
				(type default)
			)
			(layer "F.Fab")
		)
		(fp_line
			(start 0.67945 0.3048)
			(end 0.120396 0.3048)
			(stroke
				(width 0.1)
				(type default)
			)
			(layer "F.Fab")
		)
		(fp_line
			(start -0.12065 0.2794)
			(end -0.12065 0.3048)
			(stroke
				(width 0.1)
				(type default)
			)
			(layer "F.Fab")
		)
		(fp_line
			(start 0.120396 0.2794)
			(end -0.12065 0.2794)
			(stroke
				(width 0.1)
				(type default)
			)
			(layer "F.Fab")
		)
		(fp_line
			(start -0.12065 -0.2794)
			(end 0.12065 -0.2794)
			(stroke
				(width 0.1)
				(type default)
			)
			(layer "F.Fab")
		)
		(fp_line
			(start 0.12065 -0.2794)
			(end 0.12065 -0.3048)
			(stroke
				(width 0.1)
				(type default)
			)
			(layer "F.Fab")
		)
		(fp_line
			(start 0.12065 -0.3048)
			(end 0.67945 -0.3048)
			(stroke
				(width 0.1)
				(type default)
			)
			(layer "F.Fab")
		)
		(fp_line
			(start 0.67945 -0.3048)
			(end 0.67945 0.3048)
			(stroke
				(width 0.1)
				(type default)
			)
			(layer "F.Fab")
		)
		(fp_line
			(start -0.67945 -0.305054)
			(end -0.12065 -0.305054)
			(stroke
				(width 0.1)
				(type default)
			)
			(layer "F.Fab")
		)
		(fp_line
			(start -0.12065 -0.305054)
			(end -0.12065 -0.2794)
			(stroke
				(width 0.1)
				(type default)
			)
			(layer "F.Fab")
		)
		(pad "1" smd circle
			(at -0.40005 0 270)
			(size 0 0)
			(layers "F.Cu" "F.Mask" "F.Paste")
			(net "PVDD11_S3_P0_PVCC")
		)
		(pad "2" smd circle
			(at 0.40005 0 270)
			(size 0 0)
			(layers "F.Cu" "F.Mask" "F.Paste")
			(net "GND")
		)
	)
	(footprint ""
		(layer "F.Cu")
		(at 20.860258 -427.580298 -90)
		(property "Reference" "R6163"
			(at 0 0 270)
			(layer "F.SilkS")
			(hide yes)
			(effects
				(font
					(size 1.27 1.27)
				)
			)
		)
		(property "Value" ""
			(at 0 0 270)
			(layer "F.Fab")
			(effects
				(font
					(size 1.27 1.27)
				)
			)
		)
		(duplicate_pad_numbers_are_jumpers no)
		(fp_line
			(start -0.7874 0.4064)
			(end -0.7874 -0.4064)
			(stroke
				(width 0.1524)
				(type default)
			)
			(layer "F.SilkS")
		)
		(fp_line
			(start 0.7874 0.4064)
			(end -0.7874 0.4064)
			(stroke
				(width 0.1524)
				(type default)
			)
			(layer "F.SilkS")
		)
		(fp_line
			(start -0.7874 -0.4064)
			(end 0.7874 -0.4064)
			(stroke
				(width 0.1524)
				(type default)
			)
			(layer "F.SilkS")
		)
		(fp_line
			(start 0.7874 -0.4064)
			(end 0.7874 0.4064)
			(stroke
				(width 0.1524)
				(type default)
			)
			(layer "F.SilkS")
		)
		(fp_line
			(start -0.67945 0.3048)
			(end -0.67945 -0.305054)
			(stroke
				(width 0.1)
				(type default)
			)
			(layer "F.Fab")
		)
		(fp_line
			(start -0.12065 0.3048)
			(end -0.67945 0.3048)
			(stroke
				(width 0.1)
				(type default)
			)
			(layer "F.Fab")
		)
		(fp_line
			(start 0.120396 0.3048)
			(end 0.120396 0.2794)
			(stroke
				(width 0.1)
				(type default)
			)
			(layer "F.Fab")
		)
		(fp_line
			(start 0.67945 0.3048)
			(end 0.120396 0.3048)
			(stroke
				(width 0.1)
				(type default)
			)
			(layer "F.Fab")
		)
		(fp_line
			(start -0.12065 0.2794)
			(end -0.12065 0.3048)
			(stroke
				(width 0.1)
				(type default)
			)
			(layer "F.Fab")
		)
		(fp_line
			(start 0.120396 0.2794)
			(end -0.12065 0.2794)
			(stroke
				(width 0.1)
				(type default)
			)
			(layer "F.Fab")
		)
		(fp_line
			(start -0.12065 -0.2794)
			(end 0.12065 -0.2794)
			(stroke
				(width 0.1)
				(type default)
			)
			(layer "F.Fab")
		)
		(fp_line
			(start 0.12065 -0.2794)
			(end 0.12065 -0.3048)
			(stroke
				(width 0.1)
				(type default)
			)
			(layer "F.Fab")
		)
		(fp_line
			(start 0.12065 -0.3048)
			(end 0.67945 -0.3048)
			(stroke
				(width 0.1)
				(type default)
			)
			(layer "F.Fab")
		)
		(fp_line
			(start 0.67945 -0.3048)
			(end 0.67945 0.3048)
			(stroke
				(width 0.1)
				(type default)
			)
			(layer "F.Fab")
		)
		(fp_line
			(start -0.67945 -0.305054)
			(end -0.12065 -0.305054)
			(stroke
				(width 0.1)
				(type default)
			)
			(layer "F.Fab")
		)
		(fp_line
			(start -0.12065 -0.305054)
			(end -0.12065 -0.2794)
			(stroke
				(width 0.1)
				(type default)
			)
			(layer "F.Fab")
		)
		(pad "1" smd circle
			(at -0.40005 0 270)
			(size 0 0)
			(layers "F.Cu" "F.Mask" "F.Paste")
			(net "P3V3_AUX")
		)
		(pad "2" smd circle
			(at 0.40005 0 270)
			(size 0 0)
			(layers "F.Cu" "F.Mask" "F.Paste")
			(net "FM_P2E_BUF2_EQB1")
		)
	)
	(footprint ""
		(layer "F.Cu")
		(at 358.268524 -384.449828)
		(property "Reference" "C936"
			(at 0 0 0)
			(layer "F.SilkS")
			(hide yes)
			(effects
				(font
					(size 1.27 1.27)
				)
			)
		)
		(property "Value" ""
			(at 0 0 0)
			(layer "F.Fab")
			(effects
				(font
					(size 1.27 1.27)
				)
			)
		)
		(duplicate_pad_numbers_are_jumpers no)
		(fp_line
			(start -0.299974 -0.150114)
			(end 0.299974 -0.150114)
			(stroke
				(width 0.1)
				(type default)
			)
			(layer "F.Fab")
		)
		(fp_line
			(start -0.299974 0.150114)
			(end -0.299974 -0.150114)
			(stroke
				(width 0.1)
				(type default)
			)
			(layer "F.Fab")
		)
		(fp_line
			(start 0.299974 -0.150114)
			(end 0.299974 0.150114)
			(stroke
				(width 0.1)
				(type default)
			)
			(layer "F.Fab")
		)
		(fp_line
			(start 0.299974 0.150114)
			(end -0.299974 0.150114)
			(stroke
				(width 0.1)
				(type default)
			)
			(layer "F.Fab")
		)
		(pad "1" smd rect
			(at -0.2667 0)
			(size 0.3048 0.381)
			(layers "F.Cu" "F.Mask" "F.Paste")
			(net "P5E_CPU0_P1_TX_C_DN<14>")
		)
		(pad "2" smd rect
			(at 0.2667 0)
			(size 0.3048 0.381)
			(layers "F.Cu" "F.Mask" "F.Paste")
			(net "P5E_CPU0_P1_TX_DN<14>")
		)
	)
	(footprint ""
		(layer "F.Cu")
		(at 338.683346 -23.897336 -90)
		(property "Reference" "R1507"
			(at 0 0 270)
			(layer "F.SilkS")
			(hide yes)
			(effects
				(font
					(size 1.27 1.27)
				)
			)
		)
		(property "Value" ""
			(at 0 0 270)
			(layer "F.Fab")
			(effects
				(font
					(size 1.27 1.27)
				)
			)
		)
		(duplicate_pad_numbers_are_jumpers no)
		(fp_line
			(start -0.7874 0.4064)
			(end -0.7874 -0.4064)
			(stroke
				(width 0.1524)
				(type default)
			)
			(layer "F.SilkS")
		)
		(fp_line
			(start 0.7874 0.4064)
			(end -0.7874 0.4064)
			(stroke
				(width 0.1524)
				(type default)
			)
			(layer "F.SilkS")
		)
		(fp_line
			(start -0.7874 -0.4064)
			(end 0.7874 -0.4064)
			(stroke
				(width 0.1524)
				(type default)
			)
			(layer "F.SilkS")
		)
		(fp_line
			(start 0.7874 -0.4064)
			(end 0.7874 0.4064)
			(stroke
				(width 0.1524)
				(type default)
			)
			(layer "F.SilkS")
		)
		(fp_line
			(start -0.67945 0.3048)
			(end -0.67945 -0.305054)
			(stroke
				(width 0.1)
				(type default)
			)
			(layer "F.Fab")
		)
		(fp_line
			(start -0.12065 0.3048)
			(end -0.67945 0.3048)
			(stroke
				(width 0.1)
				(type default)
			)
			(layer "F.Fab")
		)
		(fp_line
			(start 0.120396 0.3048)
			(end 0.120396 0.2794)
			(stroke
				(width 0.1)
				(type default)
			)
			(layer "F.Fab")
		)
		(fp_line
			(start 0.67945 0.3048)
			(end 0.120396 0.3048)
			(stroke
				(width 0.1)
				(type default)
			)
			(layer "F.Fab")
		)
		(fp_line
			(start -0.12065 0.2794)
			(end -0.12065 0.3048)
			(stroke
				(width 0.1)
				(type default)
			)
			(layer "F.Fab")
		)
		(fp_line
			(start 0.120396 0.2794)
			(end -0.12065 0.2794)
			(stroke
				(width 0.1)
				(type default)
			)
			(layer "F.Fab")
		)
		(fp_line
			(start -0.12065 -0.2794)
			(end 0.12065 -0.2794)
			(stroke
				(width 0.1)
				(type default)
			)
			(layer "F.Fab")
		)
		(fp_line
			(start 0.12065 -0.2794)
			(end 0.12065 -0.3048)
			(stroke
				(width 0.1)
				(type default)
			)
			(layer "F.Fab")
		)
		(fp_line
			(start 0.12065 -0.3048)
			(end 0.67945 -0.3048)
			(stroke
				(width 0.1)
				(type default)
			)
			(layer "F.Fab")
		)
		(fp_line
			(start 0.67945 -0.3048)
			(end 0.67945 0.3048)
			(stroke
				(width 0.1)
				(type default)
			)
			(layer "F.Fab")
		)
		(fp_line
			(start -0.67945 -0.305054)
			(end -0.12065 -0.305054)
			(stroke
				(width 0.1)
				(type default)
			)
			(layer "F.Fab")
		)
		(fp_line
			(start -0.12065 -0.305054)
			(end -0.12065 -0.2794)
			(stroke
				(width 0.1)
				(type default)
			)
			(layer "F.Fab")
		)
		(pad "1" smd circle
			(at -0.40005 0 270)
			(size 0 0)
			(layers "F.Cu" "F.Mask" "F.Paste")
			(net "P3V3_AUX")
		)
		(pad "2" smd circle
			(at 0.40005 0 270)
			(size 0 0)
			(layers "F.Cu" "F.Mask" "F.Paste")
			(net "LED_BIOS_DBG_MODE_N")
		)
	)
)
